(kicad_pcb
	(version 20260206)
	(generator "pcbnew")
	(generator_version "10.0")
	(general
		(thickness 1.6)
		(legacy_teardrops no)
	)
	(paper "A4")
	(title_block
		(title "Bryce Canyon_F.DPB_16315-1-OCP.brd")
		(comment 1 "Bryce Canyon / footprints 2215-2222 of 2223")
	)
	(layers
		(0 "F.Cu" signal "TOP")
		(4 "In1.Cu" signal "L2GND")
		(6 "In2.Cu" signal "L3")
		(8 "In3.Cu" signal "L4GND")
		(10 "In4.Cu" signal "L5")
		(12 "In5.Cu" signal "L6VCC")
		(14 "In6.Cu" signal "L7VCC")
		(16 "In7.Cu" signal "L8")
		(18 "In8.Cu" signal "L9GND")
		(20 "In9.Cu" signal "L10")
		(22 "In10.Cu" signal "L11GND")
		(2 "B.Cu" signal "BOTTOM")
		(9 "F.Adhes" user "F.Adhesive")
		(11 "B.Adhes" user "B.Adhesive")
		(13 "F.Paste" user "Package Geometry/Pastemask Top")
		(15 "B.Paste" user "Package Geometry/Pastemask Bottom")
		(5 "F.SilkS" user "Ref Des/Silkscreen Top")
		(7 "B.SilkS" user "Ref Des/Silkscreen Bottom")
		(1 "F.Mask" user "Board Geometry/Soldermask Top")
		(3 "B.Mask" user "Board Geometry/Soldermask Bottom")
		(17 "Dwgs.User" user "User.Drawings")
		(19 "Cmts.User" user "User.Comments")
		(21 "Eco1.User" user "User.Eco1")
		(23 "Eco2.User" user "User.Eco2")
		(25 "Edge.Cuts" user "Board Geometry/Outline")
		(27 "Margin" user)
		(31 "F.CrtYd" user "Package Geometry/Place Bound Top")
		(29 "B.CrtYd" user "Package Geometry/Place Bound Bottom")
		(35 "F.Fab" user "Ref Des/Assembly Top")
		(33 "B.Fab" user "Ref Des/Assembly Bottom")
	)
	(footprint ""
		(layer "B.Cu")
		(at 188.7728 -222.5802)
		(property "Reference" "R1286"
			(at 0 0 0)
			(layer "B.SilkS")
			(hide yes)
			(effects
				(font
					(size 1.27 1.27)
				)
				(justify mirror)
			)
		)
		(property "Value" "0R2J-2-GP"
			(at -0.064008 -3.993896 0)
			(unlocked yes)
			(layer "B.Fab")
			(hide yes)
			(effects
				(font
					(size 1.016 1.016)
					(thickness 0.1524)
				)
				(justify mirror)
			)
		)
		(property "Device Type" "R402H16"
			(at -0.064008 -5.517896 0)
			(unlocked yes)
			(layer "B.Fab")
			(hide yes)
			(effects
				(font
					(size 1.016 1.016)
					(thickness 0.1524)
				)
				(justify mirror)
			)
		)
		(duplicate_pad_numbers_are_jumpers no)
		(fp_line
			(start -0.508 -0.9398)
			(end 0.508 -0.9398)
			(stroke
				(width 0.1524)
				(type default)
			)
			(layer "B.SilkS")
		)
		(fp_line
			(start 0.508 -0.9398)
			(end 0.508 0.9398)
			(stroke
				(width 0.1524)
				(type default)
			)
			(layer "B.SilkS")
		)
		(fp_rect
			(start 0.508 0.9398)
			(end -0.508 -0.9398)
			(stroke
				(width 0)
				(type default)
			)
			(fill no)
			(layer "B.CrtYd")
		)
		(fp_rect
			(start 0.508 0.9398)
			(end -0.508 -0.9398)
			(stroke
				(width 0)
				(type default)
			)
			(fill no)
			(layer "B.Fab")
		)
		(pad "1" smd custom
			(at 0 -0.4445 180)
			(size 0.1397 0.1397)
			(layers "B.Cu" "B.Mask" "B.Paste")
			(net "P3V3_STBY_VO")
			(options
				(clearance outline)
				(anchor circle)
			)
			(primitives
				(gr_poly
					(pts
						(arc
							(start -0.1778 0.2794)
							(mid -0.249642 0.249642)
							(end -0.2794 0.1778)
						)
						(arc
							(start -0.2794 -0.1778)
							(mid -0.249642 -0.249642)
							(end -0.1778 -0.2794)
						)
						(arc
							(start 0.1778 -0.2794)
							(mid 0.249642 -0.249642)
							(end 0.2794 -0.1778)
						)
						(arc
							(start 0.2794 0.1778)
							(mid 0.249642 0.249642)
							(end 0.1778 0.2794)
						)
					)
					(width 0)
					(fill yes)
				)
			)
		)
		(pad "2" smd custom
			(at 0 0.4445 180)
			(size 0.1397 0.1397)
			(layers "B.Cu" "B.Mask" "B.Paste")
			(net "P3V3_STBY_CC_R")
			(options
				(clearance outline)
				(anchor circle)
			)
			(primitives
				(gr_poly
					(pts
						(arc
							(start -0.1778 0.2794)
							(mid -0.249642 0.249642)
							(end -0.2794 0.1778)
						)
						(arc
							(start -0.2794 -0.1778)
							(mid -0.249642 -0.249642)
							(end -0.1778 -0.2794)
						)
						(arc
							(start 0.1778 -0.2794)
							(mid 0.249642 -0.249642)
							(end 0.2794 -0.1778)
						)
						(arc
							(start 0.2794 0.1778)
							(mid 0.249642 0.249642)
							(end 0.1778 0.2794)
						)
					)
					(width 0)
					(fill yes)
				)
			)
		)
	)
	(footprint ""
		(layer "B.Cu")
		(at 449.291202 -257.48615 90)
		(property "Reference" "C667"
			(at 0 0 90)
			(layer "B.SilkS")
			(hide yes)
			(effects
				(font
					(size 1.27 1.27)
				)
				(justify mirror)
			)
		)
		(property "Value" "SC68P50V2JN-2-GP"
			(at -1.1811 -2.7051 90)
			(unlocked yes)
			(layer "B.Fab")
			(hide yes)
			(effects
				(font
					(size 1.016 1.016)
					(thickness 0.1524)
				)
				(justify mirror)
			)
		)
		(property "Device Type" "C402H22"
			(at -1.1811 -4.2291 90)
			(unlocked yes)
			(layer "B.Fab")
			(hide yes)
			(effects
				(font
					(size 1.016 1.016)
					(thickness 0.1524)
				)
				(justify mirror)
			)
		)
		(duplicate_pad_numbers_are_jumpers no)
		(fp_rect
			(start 0.4318 0.9525)
			(end -0.4318 -0.9525)
			(stroke
				(width 0)
				(type default)
			)
			(fill no)
			(layer "B.CrtYd")
		)
		(fp_rect
			(start 0.4318 0.9525)
			(end -0.4318 -0.9525)
			(stroke
				(width 0)
				(type default)
			)
			(fill no)
			(layer "B.Fab")
		)
		(pad "1" smd custom
			(at 0 -0.4445 270)
			(size 0.1524 0.1524)
			(layers "B.Cu" "B.Mask" "B.Paste")
			(net "P5V_C_VFB")
			(options
				(clearance outline)
				(anchor circle)
			)
			(primitives
				(gr_poly
					(pts
						(arc
							(start 0.3048 0.2032)
							(mid 0.275042 0.275042)
							(end 0.2032 0.3048)
						)
						(arc
							(start -0.2032 0.3048)
							(mid -0.275042 0.275042)
							(end -0.3048 0.2032)
						)
						(arc
							(start -0.3048 -0.2032)
							(mid -0.275042 -0.275042)
							(end -0.2032 -0.3048)
						)
						(arc
							(start 0.2032 -0.3048)
							(mid 0.275042 -0.275042)
							(end 0.3048 -0.2032)
						)
					)
					(width 0)
					(fill yes)
				)
			)
		)
		(pad "2" smd custom
			(at 0 0.4445 270)
			(size 0.1524 0.1524)
			(layers "B.Cu" "B.Mask" "B.Paste")
			(net "P5V_C_VFB_R")
			(options
				(clearance outline)
				(anchor circle)
			)
			(primitives
				(gr_poly
					(pts
						(arc
							(start 0.3048 0.2032)
							(mid 0.275042 0.275042)
							(end 0.2032 0.3048)
						)
						(arc
							(start -0.2032 0.3048)
							(mid -0.275042 0.275042)
							(end -0.3048 0.2032)
						)
						(arc
							(start -0.3048 -0.2032)
							(mid -0.275042 -0.275042)
							(end -0.2032 -0.3048)
						)
						(arc
							(start 0.2032 -0.3048)
							(mid 0.275042 -0.275042)
							(end 0.3048 -0.2032)
						)
					)
					(width 0)
					(fill yes)
				)
			)
		)
	)
	(footprint ""
		(layer "B.Cu")
		(at 190.745872 -228.116892 180)
		(property "Reference" "C670"
			(at 0 0 0)
			(layer "B.SilkS")
			(hide yes)
			(effects
				(font
					(size 1.27 1.27)
				)
				(justify mirror)
			)
		)
		(property "Value" "SCD1U16V2KX-3GP"
			(at -1.1811 -2.7051 180)
			(unlocked yes)
			(layer "B.Fab")
			(hide yes)
			(effects
				(font
					(size 1.016 1.016)
					(thickness 0.1524)
				)
				(justify mirror)
			)
		)
		(property "Device Type" "C402H22"
			(at -1.1811 -4.2291 180)
			(unlocked yes)
			(layer "B.Fab")
			(hide yes)
			(effects
				(font
					(size 1.016 1.016)
					(thickness 0.1524)
				)
				(justify mirror)
			)
		)
		(duplicate_pad_numbers_are_jumpers no)
		(fp_rect
			(start 0.4318 0.9525)
			(end -0.4318 -0.9525)
			(stroke
				(width 0)
				(type default)
			)
			(fill no)
			(layer "B.CrtYd")
		)
		(fp_rect
			(start 0.4318 0.9525)
			(end -0.4318 -0.9525)
			(stroke
				(width 0)
				(type default)
			)
			(fill no)
			(layer "B.Fab")
		)
		(pad "1" smd custom
			(at 0 -0.4445)
			(size 0.1524 0.1524)
			(layers "B.Cu" "B.Mask" "B.Paste")
			(net "P3V3_STBY_VIN")
			(options
				(clearance outline)
				(anchor circle)
			)
			(primitives
				(gr_poly
					(pts
						(arc
							(start 0.3048 0.2032)
							(mid 0.275042 0.275042)
							(end 0.2032 0.3048)
						)
						(arc
							(start -0.2032 0.3048)
							(mid -0.275042 0.275042)
							(end -0.3048 0.2032)
						)
						(arc
							(start -0.3048 -0.2032)
							(mid -0.275042 -0.275042)
							(end -0.2032 -0.3048)
						)
						(arc
							(start 0.2032 -0.3048)
							(mid 0.275042 -0.275042)
							(end 0.3048 -0.2032)
						)
					)
					(width 0)
					(fill yes)
				)
			)
		)
		(pad "2" smd custom
			(at 0 0.4445)
			(size 0.1524 0.1524)
			(layers "B.Cu" "B.Mask" "B.Paste")
			(net "GND")
			(options
				(clearance outline)
				(anchor circle)
			)
			(primitives
				(gr_poly
					(pts
						(arc
							(start 0.3048 0.2032)
							(mid 0.275042 0.275042)
							(end 0.2032 0.3048)
						)
						(arc
							(start -0.2032 0.3048)
							(mid -0.275042 0.275042)
							(end -0.3048 0.2032)
						)
						(arc
							(start -0.3048 -0.2032)
							(mid -0.275042 -0.275042)
							(end -0.2032 -0.3048)
						)
						(arc
							(start 0.2032 -0.3048)
							(mid 0.275042 -0.275042)
							(end 0.3048 -0.2032)
						)
					)
					(width 0)
					(fill yes)
				)
			)
		)
	)
	(footprint ""
		(layer "B.Cu")
		(at 472.186 -245.11 90)
		(property "Reference" "R1264"
			(at 0 0 90)
			(layer "B.SilkS")
			(hide yes)
			(effects
				(font
					(size 1.27 1.27)
				)
				(justify mirror)
			)
		)
		(property "Value" "2D2R3-1-U-GP"
			(at 0.0254 -2.5146 90)
			(unlocked yes)
			(layer "B.Fab")
			(hide yes)
			(effects
				(font
					(size 1.016 1.016)
					(thickness 0.1524)
				)
				(justify mirror)
			)
		)
		(property "Device Type" "R603H22"
			(at 0.0254 -4.0386 90)
			(unlocked yes)
			(layer "B.Fab")
			(hide yes)
			(effects
				(font
					(size 1.016 1.016)
					(thickness 0.1524)
				)
				(justify mirror)
			)
		)
		(duplicate_pad_numbers_are_jumpers no)
		(fp_line
			(start 0.4826 0)
			(end 0.2032 0)
			(stroke
				(width 0.2032)
				(type default)
			)
			(layer "B.SilkS")
		)
		(fp_line
			(start -0.2032 0)
			(end -0.4826 0)
			(stroke
				(width 0.2032)
				(type default)
			)
			(layer "B.SilkS")
		)
		(fp_rect
			(start 0.5842 1.3335)
			(end -0.5842 -1.3335)
			(stroke
				(width 0)
				(type default)
			)
			(fill no)
			(layer "B.CrtYd")
		)
		(fp_rect
			(start 0.5842 1.3335)
			(end -0.5842 -1.3335)
			(stroke
				(width 0)
				(type default)
			)
			(fill no)
			(layer "B.Fab")
		)
		(pad "1" smd custom
			(at 0 -0.762 270)
			(size 0.2159 0.2159)
			(layers "B.Cu" "B.Mask" "B.Paste")
			(net "P12V_A")
			(options
				(clearance outline)
				(anchor circle)
			)
			(primitives
				(gr_poly
					(pts
						(arc
							(start -0.3302 0.4318)
							(mid -0.402042 0.402042)
							(end -0.4318 0.3302)
						)
						(arc
							(start -0.4318 -0.3302)
							(mid -0.402042 -0.402042)
							(end -0.3302 -0.4318)
						)
						(arc
							(start 0.3302 -0.4318)
							(mid 0.402042 -0.402042)
							(end 0.4318 -0.3302)
						)
						(arc
							(start 0.4318 0.3302)
							(mid 0.402042 0.402042)
							(end 0.3302 0.4318)
						)
					)
					(width 0)
					(fill yes)
				)
			)
		)
		(pad "2" smd custom
			(at 0 0.762 270)
			(size 0.2159 0.2159)
			(layers "B.Cu" "B.Mask" "B.Paste")
			(net "P12V_A_VDD_U27")
			(options
				(clearance outline)
				(anchor circle)
			)
			(primitives
				(gr_poly
					(pts
						(arc
							(start -0.3302 0.4318)
							(mid -0.402042 0.402042)
							(end -0.4318 0.3302)
						)
						(arc
							(start -0.4318 -0.3302)
							(mid -0.402042 -0.402042)
							(end -0.3302 -0.4318)
						)
						(arc
							(start 0.3302 -0.4318)
							(mid 0.402042 -0.402042)
							(end 0.4318 -0.3302)
						)
						(arc
							(start 0.4318 0.3302)
							(mid 0.402042 0.402042)
							(end 0.3302 0.4318)
						)
					)
					(width 0)
					(fill yes)
				)
			)
		)
	)
	(footprint ""
		(layer "B.Cu")
		(at 45.8978 -148.6662)
		(property "Reference" "PG13"
			(at 0 0 0)
			(layer "B.SilkS")
			(hide yes)
			(effects
				(font
					(size 1.27 1.27)
				)
				(justify mirror)
			)
		)
		(property "Value" "COPPER-CLOSE-GP-U"
			(at -0.0762 -2.8702 0)
			(unlocked yes)
			(layer "B.Fab")
			(hide yes)
			(effects
				(font
					(size 1.016 1.016)
					(thickness 0.1524)
				)
				(justify mirror)
			)
		)
		(property "Device Type" "CON2C-U"
			(at -0.0762 -4.3942 0)
			(unlocked yes)
			(layer "B.Fab")
			(hide yes)
			(effects
				(font
					(size 1.016 1.016)
					(thickness 0.1524)
				)
				(justify mirror)
			)
		)
		(duplicate_pad_numbers_are_jumpers no)
		(fp_rect
			(start 0.9398 0.9652)
			(end -0.9398 -0.9652)
			(stroke
				(width 0)
				(type default)
			)
			(fill no)
			(layer "B.CrtYd")
		)
		(fp_rect
			(start 0.9398 0.9652)
			(end -0.9398 -0.9652)
			(stroke
				(width 0)
				(type default)
			)
			(fill no)
			(layer "B.Fab")
		)
		(pad "1" smd custom
			(at 0 -0.5334 180)
			(size 0.17145 0.17145)
			(layers "B.Cu" "B.Mask" "B.Paste")
			(net "AGND_P5V_B")
			(options
				(clearance outline)
				(anchor circle)
			)
			(primitives
				(gr_poly
					(pts
						(xy -0.127 -0.3429) (xy -0.127 -0.1651) (xy -0.635 0.3429) (xy 0.635 0.3429) (xy 0.127 -0.1651)
						(xy 0.127 -0.3429)
					)
					(width 0)
					(fill yes)
				)
			)
		)
		(pad "2" smd custom
			(at 0 0.5334 180)
			(size 0.17145 0.17145)
			(layers "B.Cu" "B.Mask" "B.Paste")
			(net "GND")
			(options
				(clearance outline)
				(anchor circle)
			)
			(primitives
				(gr_poly
					(pts
						(xy -0.635 -0.3429) (xy -0.127 0.1651) (xy -0.127 0.3429) (xy 0.127 0.3429) (xy 0.127 0.1651)
						(xy 0.635 -0.3429)
					)
					(width 0)
					(fill yes)
				)
			)
		)
	)
	(footprint ""
		(layer "B.Cu")
		(at 455.507344 -255.949196 180)
		(property "Reference" "R1249"
			(at 0 0 0)
			(layer "B.SilkS")
			(hide yes)
			(effects
				(font
					(size 1.27 1.27)
				)
				(justify mirror)
			)
		)
		(property "Value" "2K7R2F-GP"
			(at -0.064008 -3.993896 180)
			(unlocked yes)
			(layer "B.Fab")
			(hide yes)
			(effects
				(font
					(size 1.016 1.016)
					(thickness 0.1524)
				)
				(justify mirror)
			)
		)
		(property "Device Type" "R402H16"
			(at -0.064008 -5.517896 180)
			(unlocked yes)
			(layer "B.Fab")
			(hide yes)
			(effects
				(font
					(size 1.016 1.016)
					(thickness 0.1524)
				)
				(justify mirror)
			)
		)
		(duplicate_pad_numbers_are_jumpers no)
		(fp_line
			(start 0.508 -0.9398)
			(end 0.508 0.9398)
			(stroke
				(width 0.1524)
				(type default)
			)
			(layer "B.SilkS")
		)
		(fp_line
			(start -0.508 -0.9398)
			(end 0.508 -0.9398)
			(stroke
				(width 0.1524)
				(type default)
			)
			(layer "B.SilkS")
		)
		(fp_rect
			(start 0.508 0.9398)
			(end -0.508 -0.9398)
			(stroke
				(width 0)
				(type default)
			)
			(fill no)
			(layer "B.CrtYd")
		)
		(fp_rect
			(start 0.508 0.9398)
			(end -0.508 -0.9398)
			(stroke
				(width 0)
				(type default)
			)
			(fill no)
			(layer "B.Fab")
		)
		(pad "1" smd custom
			(at 0 -0.4445)
			(size 0.1397 0.1397)
			(layers "B.Cu" "B.Mask" "B.Paste")
			(net "P5V_C_LL")
			(options
				(clearance outline)
				(anchor circle)
			)
			(primitives
				(gr_poly
					(pts
						(arc
							(start -0.1778 0.2794)
							(mid -0.249642 0.249642)
							(end -0.2794 0.1778)
						)
						(arc
							(start -0.2794 -0.1778)
							(mid -0.249642 -0.249642)
							(end -0.1778 -0.2794)
						)
						(arc
							(start 0.1778 -0.2794)
							(mid 0.249642 -0.249642)
							(end 0.2794 -0.1778)
						)
						(arc
							(start 0.2794 0.1778)
							(mid 0.249642 0.249642)
							(end 0.1778 0.2794)
						)
					)
					(width 0)
					(fill yes)
				)
			)
		)
		(pad "2" smd custom
			(at 0 0.4445)
			(size 0.1397 0.1397)
			(layers "B.Cu" "B.Mask" "B.Paste")
			(net "P5V_C_LL_R")
			(options
				(clearance outline)
				(anchor circle)
			)
			(primitives
				(gr_poly
					(pts
						(arc
							(start -0.1778 0.2794)
							(mid -0.249642 0.249642)
							(end -0.2794 0.1778)
						)
						(arc
							(start -0.2794 -0.1778)
							(mid -0.249642 -0.249642)
							(end -0.1778 -0.2794)
						)
						(arc
							(start 0.1778 -0.2794)
							(mid 0.249642 -0.249642)
							(end 0.2794 -0.1778)
						)
						(arc
							(start 0.2794 0.1778)
							(mid 0.249642 0.249642)
							(end 0.1778 0.2794)
						)
					)
					(width 0)
					(fill yes)
				)
			)
		)
	)
	(footprint ""
		(layer "B.Cu")
		(at 181.076092 -239.238028 180)
		(property "Reference" "C684"
			(at 0 0 0)
			(layer "B.SilkS")
			(hide yes)
			(effects
				(font
					(size 1.27 1.27)
				)
				(justify mirror)
			)
		)
		(property "Value" "SC10U6D3V5KX-4GP"
			(at 0.0762 -6.1214 180)
			(unlocked yes)
			(layer "B.Fab")
			(hide yes)
			(effects
				(font
					(size 1.016 1.016)
					(thickness 0.1524)
				)
				(justify mirror)
			)
		)
		(property "Device Type" "C805H58"
			(at 0.0762 -8.1534 180)
			(unlocked yes)
			(layer "B.Fab")
			(hide yes)
			(effects
				(font
					(size 1.016 1.016)
					(thickness 0.1524)
				)
				(justify mirror)
			)
		)
		(duplicate_pad_numbers_are_jumpers no)
		(fp_line
			(start -0.635 0)
			(end 0.635 0)
			(stroke
				(width 0.508)
				(type default)
			)
			(layer "B.SilkS")
		)
		(fp_rect
			(start 0.9652 1.778)
			(end -0.9652 -1.778)
			(stroke
				(width 0)
				(type default)
			)
			(fill no)
			(layer "B.CrtYd")
		)
		(fp_poly
			(pts
				(xy 0.9652 -1.778) (xy -0.9652 -1.778) (xy -0.9652 1.778) (xy 0.9652 1.778)
			)
			(stroke
				(width 0)
				(type default)
			)
			(fill no)
			(layer "B.Fab")
		)
		(pad "1" smd rect
			(at 0 -0.9652)
			(size 1.397 1.143)
			(layers "B.Cu" "B.Mask" "B.Paste")
			(net "P3V3_STBY_A")
		)
		(pad "2" smd rect
			(at 0 0.9652)
			(size 1.397 1.143)
			(layers "B.Cu" "B.Mask" "B.Paste")
			(net "GND")
		)
	)
	(footprint ""
		(layer "B.Cu")
		(at 192.304416 -219.703142 -90)
		(property "Reference" "R1284"
			(at 0 0 90)
			(layer "B.SilkS")
			(hide yes)
			(effects
				(font
					(size 1.27 1.27)
				)
				(justify mirror)
			)
		)
		(property "Value" "10R3F-GP"
			(at 0.0254 -2.5146 270)
			(unlocked yes)
			(layer "B.Fab")
			(hide yes)
			(effects
				(font
					(size 1.016 1.016)
					(thickness 0.1524)
				)
				(justify mirror)
			)
		)
		(property "Device Type" "R603H22"
			(at 0.0254 -4.0386 270)
			(unlocked yes)
			(layer "B.Fab")
			(hide yes)
			(effects
				(font
					(size 1.016 1.016)
					(thickness 0.1524)
				)
				(justify mirror)
			)
		)
		(duplicate_pad_numbers_are_jumpers no)
		(fp_line
			(start -0.2032 0)
			(end -0.4826 0)
			(stroke
				(width 0.2032)
				(type default)
			)
			(layer "B.SilkS")
		)
		(fp_line
			(start 0.4826 0)
			(end 0.2032 0)
			(stroke
				(width 0.2032)
				(type default)
			)
			(layer "B.SilkS")
		)
		(fp_rect
			(start 0.5842 1.3335)
			(end -0.5842 -1.3335)
			(stroke
				(width 0)
				(type default)
			)
			(fill no)
			(layer "B.CrtYd")
		)
		(fp_rect
			(start 0.5842 1.3335)
			(end -0.5842 -1.3335)
			(stroke
				(width 0)
				(type default)
			)
			(fill no)
			(layer "B.Fab")
		)
		(pad "1" smd custom
			(at 0 -0.762 90)
			(size 0.2159 0.2159)
			(layers "B.Cu" "B.Mask" "B.Paste")
			(net "P3V3_STBY_CC")
			(options
				(clearance outline)
				(anchor circle)
			)
			(primitives
				(gr_poly
					(pts
						(arc
							(start -0.3302 0.4318)
							(mid -0.402042 0.402042)
							(end -0.4318 0.3302)
						)
						(arc
							(start -0.4318 -0.3302)
							(mid -0.402042 -0.402042)
							(end -0.3302 -0.4318)
						)
						(arc
							(start 0.3302 -0.4318)
							(mid 0.402042 -0.402042)
							(end 0.4318 -0.3302)
						)
						(arc
							(start 0.4318 0.3302)
							(mid 0.402042 0.402042)
							(end 0.3302 0.4318)
						)
					)
					(width 0)
					(fill yes)
				)
			)
		)
		(pad "2" smd custom
			(at 0 0.762 90)
			(size 0.2159 0.2159)
			(layers "B.Cu" "B.Mask" "B.Paste")
			(net "P3V3_STBY_CC_R")
			(options
				(clearance outline)
				(anchor circle)
			)
			(primitives
				(gr_poly
					(pts
						(arc
							(start -0.3302 0.4318)
							(mid -0.402042 0.402042)
							(end -0.4318 0.3302)
						)
						(arc
							(start -0.4318 -0.3302)
							(mid -0.402042 -0.402042)
							(end -0.3302 -0.4318)
						)
						(arc
							(start 0.3302 -0.4318)
							(mid 0.402042 -0.402042)
							(end 0.4318 -0.3302)
						)
						(arc
							(start 0.4318 0.3302)
							(mid 0.402042 0.402042)
							(end 0.3302 0.4318)
						)
					)
					(width 0)
					(fill yes)
				)
			)
		)
	)
)
